# S9S_MB_2U (Grand Teton) — schematic netlist excerpt (pin names and nets, part order shuffled) for the footprints in the layout excerpt that follows; sources: Cadence DE-HDL packaged netlist, KiCad conversion of 03242023_DA0F0TMBIJ0_F0T_Motherboard_J_brd_V01_OCP.brd

PC2643  Q_CAP  1UF 25V 10% X6S  pkg C0402  page 281 : A = PVPP_HBM_CPU0_VCC ; B = GND
PR4006  Q_RES  100 1% EMPTY  pkg 0402LF  page 242 : A = P12V_SCM_R ; B = P12V_SCM_AVIN_PD

(kicad_pcb
	(version 20260206)
	(generator "pcbnew")
	(generator_version "10.0")
	(general
		(thickness 1.6)
		(legacy_teardrops no)
	)
	(paper "A4")
	(title_block
		(title "03242023_DA0F0TMBIJ0_F0T_Motherboard_J_brd_V01_OCP.brd")
		(comment 1 "Grand Teton / footprints 2900-2901 of 6105")
	)
	(layers
		(0 "F.Cu" signal "TOP")
		(4 "In1.Cu" signal "GND")
		(6 "In2.Cu" signal "IN1")
		(8 "In3.Cu" signal "GND1")
		(10 "In4.Cu" signal "IN2")
		(12 "In5.Cu" signal "GND2")
		(14 "In6.Cu" signal "IN3")
		(16 "In7.Cu" signal "GND3")
		(18 "In8.Cu" signal "VCC")
		(20 "In9.Cu" signal "VCC1")
		(22 "In10.Cu" signal "GND4")
		(24 "In11.Cu" signal "IN4")
		(26 "In12.Cu" signal "GND5")
		(28 "In13.Cu" signal "IN5")
		(30 "In14.Cu" signal "GND6")
		(32 "In15.Cu" signal "IN6")
		(34 "In16.Cu" signal "GND7")
		(2 "B.Cu" signal "BOTTOM")
		(9 "F.Adhes" user "F.Adhesive")
		(11 "B.Adhes" user "B.Adhesive")
		(13 "F.Paste" user "Package Geometry/Pastemask Top")
		(15 "B.Paste" user "Package Geometry/Pastemask Bottom")
		(5 "F.SilkS" user "Ref Des/Silkscreen Top")
		(7 "B.SilkS" user "Ref Des/Silkscreen Bottom")
		(1 "F.Mask" user "Board Geometry/Soldermask Top")
		(3 "B.Mask" user "Board Geometry/Soldermask Bottom")
		(17 "Dwgs.User" user "User.Drawings")
		(19 "Cmts.User" user "User.Comments")
		(21 "Eco1.User" user "User.Eco1")
		(23 "Eco2.User" user "User.Eco2")
		(25 "Edge.Cuts" user "Board Geometry/Outline")
		(27 "Margin" user)
		(31 "F.CrtYd" user "Package Geometry/Place Bound Top")
		(29 "B.CrtYd" user "Package Geometry/Place Bound Bottom")
		(35 "F.Fab" user "Ref Des/Assembly Top")
		(33 "B.Fab" user "Ref Des/Assembly Bottom")
	)
	(footprint ""
		(layer "F.Cu")
		(at 376.488198 -359.871518 -90)
		(property "Reference" "PC2643"
			(at 0 0 270)
			(layer "F.SilkS")
			(hide yes)
			(effects
				(font
					(size 1.27 1.27)
				)
			)
		)
		(property "Value" ""
			(at 0 0 270)
			(layer "F.Fab")
			(effects
				(font
					(size 1.27 1.27)
				)
			)
		)
		(duplicate_pad_numbers_are_jumpers no)
		(fp_line
			(start -0.7874 0.4064)
			(end -0.7874 -0.4064)
			(stroke
				(width 0.1524)
				(type default)
			)
			(layer "F.SilkS")
		)
		(fp_line
			(start 0.7874 0.4064)
			(end -0.7874 0.4064)
			(stroke
				(width 0.1524)
				(type default)
			)
			(layer "F.SilkS")
		)
		(fp_line
			(start -0.7874 -0.4064)
			(end 0.7874 -0.4064)
			(stroke
				(width 0.1524)
				(type default)
			)
			(layer "F.SilkS")
		)
		(fp_line
			(start 0.7874 -0.4064)
			(end 0.7874 0.4064)
			(stroke
				(width 0.1524)
				(type default)
			)
			(layer "F.SilkS")
		)
		(fp_line
			(start -0.67945 0.3048)
			(end -0.67945 -0.305054)
			(stroke
				(width 0.1)
				(type default)
			)
			(layer "F.Fab")
		)
		(fp_line
			(start -0.12065 0.3048)
			(end -0.67945 0.3048)
			(stroke
				(width 0.1)
				(type default)
			)
			(layer "F.Fab")
		)
		(fp_line
			(start 0.120396 0.3048)
			(end 0.120396 0.2794)
			(stroke
				(width 0.1)
				(type default)
			)
			(layer "F.Fab")
		)
		(fp_line
			(start 0.67945 0.3048)
			(end 0.120396 0.3048)
			(stroke
				(width 0.1)
				(type default)
			)
			(layer "F.Fab")
		)
		(fp_line
			(start -0.12065 0.2794)
			(end -0.12065 0.3048)
			(stroke
				(width 0.1)
				(type default)
			)
			(layer "F.Fab")
		)
		(fp_line
			(start 0.120396 0.2794)
			(end -0.12065 0.2794)
			(stroke
				(width 0.1)
				(type default)
			)
			(layer "F.Fab")
		)
		(fp_line
			(start -0.12065 -0.2794)
			(end 0.12065 -0.2794)
			(stroke
				(width 0.1)
				(type default)
			)
			(layer "F.Fab")
		)
		(fp_line
			(start 0.12065 -0.2794)
			(end 0.12065 -0.3048)
			(stroke
				(width 0.1)
				(type default)
			)
			(layer "F.Fab")
		)
		(fp_line
			(start 0.12065 -0.3048)
			(end 0.67945 -0.3048)
			(stroke
				(width 0.1)
				(type default)
			)
			(layer "F.Fab")
		)
		(fp_line
			(start 0.67945 -0.3048)
			(end 0.67945 0.3048)
			(stroke
				(width 0.1)
				(type default)
			)
			(layer "F.Fab")
		)
		(fp_line
			(start -0.67945 -0.305054)
			(end -0.12065 -0.305054)
			(stroke
				(width 0.1)
				(type default)
			)
			(layer "F.Fab")
		)
		(fp_line
			(start -0.12065 -0.305054)
			(end -0.12065 -0.2794)
			(stroke
				(width 0.1)
				(type default)
			)
			(layer "F.Fab")
		)
		(pad "1" smd circle
			(at -0.40005 0 270)
			(size 0 0)
			(layers "F.Cu" "F.Mask" "F.Paste")
			(net "PVPP_HBM_CPU0_VCC")
		)
		(pad "2" smd circle
			(at 0.40005 0 270)
			(size 0 0)
			(layers "F.Cu" "F.Mask" "F.Paste")
			(net "GND")
		)
	)
	(footprint ""
		(layer "F.Cu")
		(at 175.883062 -23.283672 180)
		(property "Reference" "PR4006"
			(at 0 0 180)
			(layer "F.SilkS")
			(hide yes)
			(effects
				(font
					(size 1.27 1.27)
				)
			)
		)
		(property "Value" ""
			(at 0 0 180)
			(layer "F.Fab")
			(effects
				(font
					(size 1.27 1.27)
				)
			)
		)
		(duplicate_pad_numbers_are_jumpers no)
		(fp_line
			(start 0.7874 0.4064)
			(end -0.7874 0.4064)
			(stroke
				(width 0.1524)
				(type default)
			)
			(layer "F.SilkS")
		)
		(fp_line
			(start 0.7874 -0.4064)
			(end 0.7874 0.4064)
			(stroke
				(width 0.1524)
				(type default)
			)
			(layer "F.SilkS")
		)
		(fp_line
			(start -0.7874 0.4064)
			(end -0.7874 -0.4064)
			(stroke
				(width 0.1524)
				(type default)
			)
			(layer "F.SilkS")
		)
		(fp_line
			(start -0.7874 -0.4064)
			(end 0.7874 -0.4064)
			(stroke
				(width 0.1524)
				(type default)
			)
			(layer "F.SilkS")
		)
		(fp_line
			(start 0.67945 0.3048)
			(end 0.120396 0.3048)
			(stroke
				(width 0.1)
				(type default)
			)
			(layer "F.Fab")
		)
		(fp_line
			(start 0.67945 -0.3048)
			(end 0.67945 0.3048)
			(stroke
				(width 0.1)
				(type default)
			)
			(layer "F.Fab")
		)
		(fp_line
			(start 0.12065 -0.2794)
			(end 0.12065 -0.3048)
			(stroke
				(width 0.1)
				(type default)
			)
			(layer "F.Fab")
		)
		(fp_line
			(start 0.12065 -0.3048)
			(end 0.67945 -0.3048)
			(stroke
				(width 0.1)
				(type default)
			)
			(layer "F.Fab")
		)
		(fp_line
			(start 0.120396 0.3048)
			(end 0.120396 0.2794)
			(stroke
				(width 0.1)
				(type default)
			)
			(layer "F.Fab")
		)
		(fp_line
			(start 0.120396 0.2794)
			(end -0.12065 0.2794)
			(stroke
				(width 0.1)
				(type default)
			)
			(layer "F.Fab")
		)
		(fp_line
			(start -0.12065 0.3048)
			(end -0.67945 0.3048)
			(stroke
				(width 0.1)
				(type default)
			)
			(layer "F.Fab")
		)
		(fp_line
			(start -0.12065 0.2794)
			(end -0.12065 0.3048)
			(stroke
				(width 0.1)
				(type default)
			)
			(layer "F.Fab")
		)
		(fp_line
			(start -0.12065 -0.2794)
			(end 0.12065 -0.2794)
			(stroke
				(width 0.1)
				(type default)
			)
			(layer "F.Fab")
		)
		(fp_line
			(start -0.12065 -0.305054)
			(end -0.12065 -0.2794)
			(stroke
				(width 0.1)
				(type default)
			)
			(layer "F.Fab")
		)
		(fp_line
			(start -0.67945 0.3048)
			(end -0.67945 -0.305054)
			(stroke
				(width 0.1)
				(type default)
			)
			(layer "F.Fab")
		)
		(fp_line
			(start -0.67945 -0.305054)
			(end -0.12065 -0.305054)
			(stroke
				(width 0.1)
				(type default)
			)
			(layer "F.Fab")
		)
		(pad "1" smd circle
			(at -0.40005 0 180)
			(size 0 0)
			(layers "F.Cu" "F.Mask" "F.Paste")
			(net "P12V_SCM_R")
		)
		(pad "2" smd circle
			(at 0.40005 0 180)
			(size 0 0)
			(layers "F.Cu" "F.Mask" "F.Paste")
			(net "P12V_SCM_AVIN_PD")
		)
	)
)
